# S9S_MB_2U (Grand Teton) — schematic netlist excerpt (pin names and nets, part order shuffled) for the footprints in the layout excerpt that follows; sources: Cadence DE-HDL packaged netlist, KiCad conversion of 03242023_DA0F0TMBIJ0_F0T_Motherboard_J_brd_V01_OCP.brd

PR138  Q_RES  8.87K 1% EMPTY  pkg 0402LF  page 269 : A = PVCCIN_CPU0_LSET6 ; B = GND
PC1176_P0_4  Q_CAP  1UF 16V 10% X6S  pkg C0402  page 272 : A = SW_P12V_PVCCFA_EHV_FIVRA_CPU0_L ; B = GND

(kicad_pcb
	(version 20260206)
	(generator "pcbnew")
	(generator_version "10.0")
	(general
		(thickness 1.6)
		(legacy_teardrops no)
	)
	(paper "A4")
	(title_block
		(title "03242023_DA0F0TMBIJ0_F0T_Motherboard_J_brd_V01_OCP.brd")
		(comment 1 "Grand Teton / footprints 2937-2938 of 6105")
	)
	(layers
		(0 "F.Cu" signal "TOP")
		(4 "In1.Cu" signal "GND")
		(6 "In2.Cu" signal "IN1")
		(8 "In3.Cu" signal "GND1")
		(10 "In4.Cu" signal "IN2")
		(12 "In5.Cu" signal "GND2")
		(14 "In6.Cu" signal "IN3")
		(16 "In7.Cu" signal "GND3")
		(18 "In8.Cu" signal "VCC")
		(20 "In9.Cu" signal "VCC1")
		(22 "In10.Cu" signal "GND4")
		(24 "In11.Cu" signal "IN4")
		(26 "In12.Cu" signal "GND5")
		(28 "In13.Cu" signal "IN5")
		(30 "In14.Cu" signal "GND6")
		(32 "In15.Cu" signal "IN6")
		(34 "In16.Cu" signal "GND7")
		(2 "B.Cu" signal "BOTTOM")
		(9 "F.Adhes" user "F.Adhesive")
		(11 "B.Adhes" user "B.Adhesive")
		(13 "F.Paste" user "Package Geometry/Pastemask Top")
		(15 "B.Paste" user "Package Geometry/Pastemask Bottom")
		(5 "F.SilkS" user "Ref Des/Silkscreen Top")
		(7 "B.SilkS" user "Ref Des/Silkscreen Bottom")
		(1 "F.Mask" user "Board Geometry/Soldermask Top")
		(3 "B.Mask" user "Board Geometry/Soldermask Bottom")
		(17 "Dwgs.User" user "User.Drawings")
		(19 "Cmts.User" user "User.Comments")
		(21 "Eco1.User" user "User.Eco1")
		(23 "Eco2.User" user "User.Eco2")
		(25 "Edge.Cuts" user "Board Geometry/Outline")
		(27 "Margin" user)
		(31 "F.CrtYd" user "Package Geometry/Place Bound Top")
		(29 "B.CrtYd" user "Package Geometry/Place Bound Bottom")
		(35 "F.Fab" user "Ref Des/Assembly Top")
		(33 "B.Fab" user "Ref Des/Assembly Bottom")
	)
	(footprint ""
		(layer "F.Cu")
		(at 292.357302 -362.843826 -90)
		(property "Reference" "PC1176_P0_4"
			(at 0 0 270)
			(layer "F.SilkS")
			(hide yes)
			(effects
				(font
					(size 1.27 1.27)
				)
			)
		)
		(property "Value" ""
			(at 0 0 270)
			(layer "F.Fab")
			(effects
				(font
					(size 1.27 1.27)
				)
			)
		)
		(duplicate_pad_numbers_are_jumpers no)
		(fp_line
			(start -0.7874 0.4064)
			(end -0.7874 -0.4064)
			(stroke
				(width 0.1524)
				(type default)
			)
			(layer "F.SilkS")
		)
		(fp_line
			(start 0.7874 0.4064)
			(end -0.7874 0.4064)
			(stroke
				(width 0.1524)
				(type default)
			)
			(layer "F.SilkS")
		)
		(fp_line
			(start -0.7874 -0.4064)
			(end 0.7874 -0.4064)
			(stroke
				(width 0.1524)
				(type default)
			)
			(layer "F.SilkS")
		)
		(fp_line
			(start 0.7874 -0.4064)
			(end 0.7874 0.4064)
			(stroke
				(width 0.1524)
				(type default)
			)
			(layer "F.SilkS")
		)
		(fp_line
			(start -0.67945 0.3048)
			(end -0.67945 -0.305054)
			(stroke
				(width 0.1)
				(type default)
			)
			(layer "F.Fab")
		)
		(fp_line
			(start -0.12065 0.3048)
			(end -0.67945 0.3048)
			(stroke
				(width 0.1)
				(type default)
			)
			(layer "F.Fab")
		)
		(fp_line
			(start 0.120396 0.3048)
			(end 0.120396 0.2794)
			(stroke
				(width 0.1)
				(type default)
			)
			(layer "F.Fab")
		)
		(fp_line
			(start 0.67945 0.3048)
			(end 0.120396 0.3048)
			(stroke
				(width 0.1)
				(type default)
			)
			(layer "F.Fab")
		)
		(fp_line
			(start -0.12065 0.2794)
			(end -0.12065 0.3048)
			(stroke
				(width 0.1)
				(type default)
			)
			(layer "F.Fab")
		)
		(fp_line
			(start 0.120396 0.2794)
			(end -0.12065 0.2794)
			(stroke
				(width 0.1)
				(type default)
			)
			(layer "F.Fab")
		)
		(fp_line
			(start -0.12065 -0.2794)
			(end 0.12065 -0.2794)
			(stroke
				(width 0.1)
				(type default)
			)
			(layer "F.Fab")
		)
		(fp_line
			(start 0.12065 -0.2794)
			(end 0.12065 -0.3048)
			(stroke
				(width 0.1)
				(type default)
			)
			(layer "F.Fab")
		)
		(fp_line
			(start 0.12065 -0.3048)
			(end 0.67945 -0.3048)
			(stroke
				(width 0.1)
				(type default)
			)
			(layer "F.Fab")
		)
		(fp_line
			(start 0.67945 -0.3048)
			(end 0.67945 0.3048)
			(stroke
				(width 0.1)
				(type default)
			)
			(layer "F.Fab")
		)
		(fp_line
			(start -0.67945 -0.305054)
			(end -0.12065 -0.305054)
			(stroke
				(width 0.1)
				(type default)
			)
			(layer "F.Fab")
		)
		(fp_line
			(start -0.12065 -0.305054)
			(end -0.12065 -0.2794)
			(stroke
				(width 0.1)
				(type default)
			)
			(layer "F.Fab")
		)
		(pad "1" smd circle
			(at -0.40005 0 270)
			(size 0 0)
			(layers "F.Cu" "F.Mask" "F.Paste")
			(net "SW_P12V_PVCCFA_EHV_FIVRA_CPU0_L")
		)
		(pad "2" smd circle
			(at 0.40005 0 270)
			(size 0 0)
			(layers "F.Cu" "F.Mask" "F.Paste")
			(net "GND")
		)
	)
	(footprint ""
		(layer "F.Cu")
		(at 335.48574 -342.270334)
		(property "Reference" "PR138"
			(at 0 0 0)
			(layer "F.SilkS")
			(hide yes)
			(effects
				(font
					(size 1.27 1.27)
				)
			)
		)
		(property "Value" ""
			(at 0 0 0)
			(layer "F.Fab")
			(effects
				(font
					(size 1.27 1.27)
				)
			)
		)
		(duplicate_pad_numbers_are_jumpers no)
		(fp_line
			(start -0.7874 -0.4064)
			(end 0.7874 -0.4064)
			(stroke
				(width 0.1524)
				(type default)
			)
			(layer "F.SilkS")
		)
		(fp_line
			(start -0.7874 0.4064)
			(end -0.7874 -0.4064)
			(stroke
				(width 0.1524)
				(type default)
			)
			(layer "F.SilkS")
		)
		(fp_line
			(start 0.7874 -0.4064)
			(end 0.7874 0.4064)
			(stroke
				(width 0.1524)
				(type default)
			)
			(layer "F.SilkS")
		)
		(fp_line
			(start 0.7874 0.4064)
			(end -0.7874 0.4064)
			(stroke
				(width 0.1524)
				(type default)
			)
			(layer "F.SilkS")
		)
		(fp_line
			(start -0.67945 -0.305054)
			(end -0.12065 -0.305054)
			(stroke
				(width 0.1)
				(type default)
			)
			(layer "F.Fab")
		)
		(fp_line
			(start -0.67945 0.3048)
			(end -0.67945 -0.305054)
			(stroke
				(width 0.1)
				(type default)
			)
			(layer "F.Fab")
		)
		(fp_line
			(start -0.12065 -0.305054)
			(end -0.12065 -0.2794)
			(stroke
				(width 0.1)
				(type default)
			)
			(layer "F.Fab")
		)
		(fp_line
			(start -0.12065 -0.2794)
			(end 0.12065 -0.2794)
			(stroke
				(width 0.1)
				(type default)
			)
			(layer "F.Fab")
		)
		(fp_line
			(start -0.12065 0.2794)
			(end -0.12065 0.3048)
			(stroke
				(width 0.1)
				(type default)
			)
			(layer "F.Fab")
		)
		(fp_line
			(start -0.12065 0.3048)
			(end -0.67945 0.3048)
			(stroke
				(width 0.1)
				(type default)
			)
			(layer "F.Fab")
		)
		(fp_line
			(start 0.120396 0.2794)
			(end -0.12065 0.2794)
			(stroke
				(width 0.1)
				(type default)
			)
			(layer "F.Fab")
		)
		(fp_line
			(start 0.120396 0.3048)
			(end 0.120396 0.2794)
			(stroke
				(width 0.1)
				(type default)
			)
			(layer "F.Fab")
		)
		(fp_line
			(start 0.12065 -0.3048)
			(end 0.67945 -0.3048)
			(stroke
				(width 0.1)
				(type default)
			)
			(layer "F.Fab")
		)
		(fp_line
			(start 0.12065 -0.2794)
			(end 0.12065 -0.3048)
			(stroke
				(width 0.1)
				(type default)
			)
			(layer "F.Fab")
		)
		(fp_line
			(start 0.67945 -0.3048)
			(end 0.67945 0.3048)
			(stroke
				(width 0.1)
				(type default)
			)
			(layer "F.Fab")
		)
		(fp_line
			(start 0.67945 0.3048)
			(end 0.120396 0.3048)
			(stroke
				(width 0.1)
				(type default)
			)
			(layer "F.Fab")
		)
		(pad "1" smd circle
			(at -0.40005 0)
			(size 0 0)
			(layers "F.Cu" "F.Mask" "F.Paste")
			(net "PVCCIN_CPU0_LSET6")
		)
		(pad "2" smd circle
			(at 0.40005 0)
			(size 0 0)
			(layers "F.Cu" "F.Mask" "F.Paste")
			(net "GND")
		)
	)
)
